(kicad_pcb
	(version 20260206)
	(generator "pcbnew")
	(generator_version "10.0")
	(general
		(thickness 1.6)
		(legacy_teardrops no)
	)
	(paper "A4")
	(title_block
		(title "01162023_DA0F0TEBIF0_F0T_Expander_BD_F_brd_V02_OCP.brd")
		(comment 1 "Grand Teton / footprints 1124-1128 of 9728")
	)
	(layers
		(0 "F.Cu" signal "TOP")
		(4 "In1.Cu" signal "GND")
		(6 "In2.Cu" signal "VCC")
		(8 "In3.Cu" signal "VCC1")
		(10 "In4.Cu" signal "GND1")
		(12 "In5.Cu" signal "IN1")
		(14 "In6.Cu" signal "GND2")
		(16 "In7.Cu" signal "IN2")
		(18 "In8.Cu" signal "GND3")
		(20 "In9.Cu" signal "IN3")
		(22 "In10.Cu" signal "GND4")
		(24 "In11.Cu" signal "IN4")
		(26 "In12.Cu" signal "GND5")
		(28 "In13.Cu" signal "IN5")
		(30 "In14.Cu" signal "GND6")
		(32 "In15.Cu" signal "IN6")
		(34 "In16.Cu" signal "GND7")
		(2 "B.Cu" signal "BOTTOM")
		(9 "F.Adhes" user "F.Adhesive")
		(11 "B.Adhes" user "B.Adhesive")
		(13 "F.Paste" user "Package Geometry/Pastemask Top")
		(15 "B.Paste" user "Package Geometry/Pastemask Bottom")
		(5 "F.SilkS" user "Ref Des/Silkscreen Top")
		(7 "B.SilkS" user "Ref Des/Silkscreen Bottom")
		(1 "F.Mask" user "Board Geometry/Soldermask Top")
		(3 "B.Mask" user "Board Geometry/Soldermask Bottom")
		(17 "Dwgs.User" user "User.Drawings")
		(19 "Cmts.User" user "User.Comments")
		(21 "Eco1.User" user "User.Eco1")
		(23 "Eco2.User" user "User.Eco2")
		(25 "Edge.Cuts" user "Board Geometry/Outline")
		(27 "Margin" user)
		(31 "F.CrtYd" user "Package Geometry/Place Bound Top")
		(29 "B.CrtYd" user "Package Geometry/Place Bound Bottom")
		(35 "F.Fab" user "Ref Des/Assembly Top")
		(33 "B.Fab" user "Ref Des/Assembly Bottom")
	)
	(footprint ""
		(layer "F.Cu")
		(at 283.811472 -71.458074 -90)
		(property "Reference" "PD112"
			(at 4.300474 -2.752598 90)
			(unlocked yes)
			(layer "F.SilkS")
			(effects
				(font
					(size 0.7874 0.5842)
					(thickness 0.1524)
				)
				(justify left)
			)
		)
		(property "Value" ""
			(at 0 0 270)
			(layer "F.Fab")
			(effects
				(font
					(size 1.27 1.27)
				)
			)
		)
		(duplicate_pad_numbers_are_jumpers no)
		(fp_line
			(start -3.656584 1.970024)
			(end 4.240784 1.970024)
			(stroke
				(width 0.1524)
				(type default)
			)
			(layer "F.SilkS")
		)
		(fp_line
			(start 4.240784 1.970024)
			(end 4.240784 -1.970024)
			(stroke
				(width 0.1524)
				(type default)
			)
			(layer "F.SilkS")
		)
		(fp_line
			(start -3.656584 -1.970024)
			(end -3.656584 1.970024)
			(stroke
				(width 0.1524)
				(type default)
			)
			(layer "F.SilkS")
		)
		(fp_line
			(start 4.240784 -1.970024)
			(end -3.656584 -1.970024)
			(stroke
				(width 0.1524)
				(type default)
			)
			(layer "F.SilkS")
		)
		(fp_poly
			(pts
				(xy 3.580384 1.970024) (xy 3.580384 -1.970024) (xy 4.240784 -1.970024) (xy 4.240784 1.970024)
			)
			(stroke
				(width 0)
				(type default)
			)
			(fill yes)
			(layer "F.SilkS")
		)
		(fp_line
			(start -2.3749 1.970024)
			(end 2.3749 1.970024)
			(stroke
				(width 0.1)
				(type default)
			)
			(layer "F.Fab")
		)
		(fp_line
			(start 2.3749 1.970024)
			(end 2.3749 -1.970024)
			(stroke
				(width 0.1)
				(type default)
			)
			(layer "F.Fab")
		)
		(fp_line
			(start -2.3749 -1.970024)
			(end -2.3749 1.970024)
			(stroke
				(width 0.1)
				(type default)
			)
			(layer "F.Fab")
		)
		(fp_line
			(start 2.3749 -1.970024)
			(end -2.3749 -1.970024)
			(stroke
				(width 0.1)
				(type default)
			)
			(layer "F.Fab")
		)
		(fp_text user "+"
			(at -4.9784 -0.23495 270)
			(unlocked yes)
			(layer "F.Fab")
			(effects
				(font
					(size 1.905 1.4224)
					(thickness 0.1524)
				)
				(justify left)
			)
		)
		(fp_text user "-"
			(at 4.1656 -0.23495 270)
			(unlocked yes)
			(layer "F.Fab")
			(effects
				(font
					(size 1.905 1.4224)
					(thickness 0.1524)
				)
				(justify left)
			)
		)
		(pad "A" smd rect
			(at -2.450084 0 270)
			(size 2.159 2.2606)
			(layers "F.Cu" "F.Mask" "F.Paste")
			(net "GND")
		)
		(pad "C" smd rect
			(at 2.450084 0 270)
			(size 2.159 2.2606)
			(layers "F.Cu" "F.Mask" "F.Paste")
			(net "P12V_AUX")
		)
	)
	(footprint ""
		(layer "F.Cu")
		(at 338.266024 18.035524)
		(property "Reference" "DE04F_2"
			(at -3.6068 -2.962148 0)
			(unlocked yes)
			(layer "F.SilkS")
			(effects
				(font
					(size 0.7874 0.5842)
					(thickness 0.1524)
				)
				(justify left)
			)
		)
		(property "Value" ""
			(at 0 0 0)
			(layer "F.Fab")
			(effects
				(font
					(size 1.27 1.27)
				)
			)
		)
		(duplicate_pad_numbers_are_jumpers no)
		(fp_line
			(start -1.2192 -2.1082)
			(end 1.2192 -2.1082)
			(stroke
				(width 0.1524)
				(type default)
			)
			(layer "F.SilkS")
		)
		(fp_line
			(start -1.2192 2.1082)
			(end -1.2192 -2.1082)
			(stroke
				(width 0.1524)
				(type default)
			)
			(layer "F.SilkS")
		)
		(fp_line
			(start 1.2192 -2.1082)
			(end 1.2192 2.1082)
			(stroke
				(width 0.1524)
				(type default)
			)
			(layer "F.SilkS")
		)
		(fp_line
			(start 1.2192 2.1082)
			(end -1.2192 2.1082)
			(stroke
				(width 0.1524)
				(type default)
			)
			(layer "F.SilkS")
		)
		(pad "" np_thru_hole circle
			(at -2.8829 -1.27 270)
			(size 1.0414 1.0414)
			(drill 1.0414)
			(layers "*.Cu" "*.Mask")
			(clearance 0.381)
			(thermal_gap 0.381)
		)
		(pad "" np_thru_hole circle
			(at -2.8829 1.27 270)
			(size 1.0414 1.0414)
			(drill 1.0414)
			(layers "*.Cu" "*.Mask")
			(clearance 0.381)
			(thermal_gap 0.381)
		)
		(pad "" np_thru_hole circle
			(at 3.4671 -1.27 270)
			(size 1.0414 1.0414)
			(drill 1.0414)
			(layers "*.Cu" "*.Mask")
			(clearance 0.381)
			(thermal_gap 0.381)
		)
		(pad "" np_thru_hole circle
			(at 3.4671 1.27 270)
			(size 1.0414 1.0414)
			(drill 1.0414)
			(layers "*.Cu" "*.Mask")
			(clearance 0.381)
			(thermal_gap 0.381)
		)
		(pad "1" smd rect
			(at 0.8255 -0.249936 270)
			(size 0.3048 0.508)
			(layers "F.Cu" "F.Mask" "F.Paste")
			(net "85_5INCH_IN2_DP")
		)
		(pad "2" smd rect
			(at 0.8255 0.249936 270)
			(size 0.3048 0.508)
			(layers "F.Cu" "F.Mask" "F.Paste")
			(net "85_5INCH_IN2_DN")
		)
		(pad "3" smd circle
			(at 0 0)
			(size 0 0)
			(layers "F.Cu" "F.Mask" "F.Paste")
			(net "COUPON_GND2")
		)
		(zone
			(layer "F.Cu")
			(hatch none 0.5)
			(connect_pads
				(clearance 0)
			)
			(min_thickness 0.25)
			(keepout
				(tracks not_allowed)
				(vias allowed)
				(pads allowed)
				(copperpour not_allowed)
				(footprints allowed)
			)
			(placement
				(enabled no)
				(sheetname "")
			)
			(fill
				(thermal_gap 0.5)
				(thermal_bridge_width 0.5)
				(island_removal_mode 0)
			)
			(polygon
				(pts
					(xy 339.383624 17.486884) (xy 339.383624 17.582388) (xy 338.786724 17.582388) (xy 338.786724 17.988788)
					(xy 339.383624 17.988788) (xy 339.383624 18.08226) (xy 338.786724 18.08226) (xy 338.786724 18.48866)
					(xy 339.383624 18.48866) (xy 339.383624 18.584164) (xy 338.685124 18.584164) (xy 338.685124 17.486884)
				)
			)
		)
		(zone
			(layers "F.Cu" "B.Cu" "In1.Cu" "In2.Cu" "In3.Cu" "In4.Cu" "In5.Cu" "In6.Cu"
				"In7.Cu" "In8.Cu" "In9.Cu" "In10.Cu" "In11.Cu" "In12.Cu" "In13.Cu" "In14.Cu"
				"In15.Cu" "In16.Cu"
			)
			(hatch none 0.5)
			(connect_pads
				(clearance 0)
			)
			(min_thickness 0.25)
			(keepout
				(tracks not_allowed)
				(vias allowed)
				(pads allowed)
				(copperpour not_allowed)
				(footprints allowed)
			)
			(placement
				(enabled no)
				(sheetname "")
			)
			(fill
				(thermal_gap 0.5)
				(thermal_bridge_width 0.5)
				(island_removal_mode 0)
			)
			(polygon
				(pts
					(arc
						(start 336.310224 16.765524)
						(mid 334.456024 16.765524)
						(end 336.310224 16.765524)
					)
				)
			)
		)
		(zone
			(layers "F.Cu" "B.Cu" "In1.Cu" "In2.Cu" "In3.Cu" "In4.Cu" "In5.Cu" "In6.Cu"
				"In7.Cu" "In8.Cu" "In9.Cu" "In10.Cu" "In11.Cu" "In12.Cu" "In13.Cu" "In14.Cu"
				"In15.Cu" "In16.Cu"
			)
			(hatch none 0.5)
			(connect_pads
				(clearance 0)
			)
			(min_thickness 0.25)
			(keepout
				(tracks not_allowed)
				(vias allowed)
				(pads allowed)
				(copperpour not_allowed)
				(footprints allowed)
			)
			(placement
				(enabled no)
				(sheetname "")
			)
			(fill
				(thermal_gap 0.5)
				(thermal_bridge_width 0.5)
				(island_removal_mode 0)
			)
			(polygon
				(pts
					(arc
						(start 336.310224 19.305524)
						(mid 334.456024 19.305524)
						(end 336.310224 19.305524)
					)
				)
			)
		)
		(zone
			(layers "F.Cu" "B.Cu" "In1.Cu" "In2.Cu" "In3.Cu" "In4.Cu" "In5.Cu" "In6.Cu"
				"In7.Cu" "In8.Cu" "In9.Cu" "In10.Cu" "In11.Cu" "In12.Cu" "In13.Cu" "In14.Cu"
				"In15.Cu" "In16.Cu"
			)
			(hatch none 0.5)
			(connect_pads
				(clearance 0)
			)
			(min_thickness 0.25)
			(keepout
				(tracks not_allowed)
				(vias allowed)
				(pads allowed)
				(copperpour not_allowed)
				(footprints allowed)
			)
			(placement
				(enabled no)
				(sheetname "")
			)
			(fill
				(thermal_gap 0.5)
				(thermal_bridge_width 0.5)
				(island_removal_mode 0)
			)
			(polygon
				(pts
					(arc
						(start 342.660224 16.765524)
						(mid 340.806024 16.765524)
						(end 342.660224 16.765524)
					)
				)
			)
		)
		(zone
			(layers "F.Cu" "B.Cu" "In1.Cu" "In2.Cu" "In3.Cu" "In4.Cu" "In5.Cu" "In6.Cu"
				"In7.Cu" "In8.Cu" "In9.Cu" "In10.Cu" "In11.Cu" "In12.Cu" "In13.Cu" "In14.Cu"
				"In15.Cu" "In16.Cu"
			)
			(hatch none 0.5)
			(connect_pads
				(clearance 0)
			)
			(min_thickness 0.25)
			(keepout
				(tracks not_allowed)
				(vias allowed)
				(pads allowed)
				(copperpour not_allowed)
				(footprints allowed)
			)
			(placement
				(enabled no)
				(sheetname "")
			)
			(fill
				(thermal_gap 0.5)
				(thermal_bridge_width 0.5)
				(island_removal_mode 0)
			)
			(polygon
				(pts
					(arc
						(start 342.660224 19.305524)
						(mid 340.806024 19.305524)
						(end 342.660224 19.305524)
					)
				)
			)
		)
	)
	(footprint ""
		(layer "F.Cu")
		(at 147.554442 -250.070874 -90)
		(property "Reference" "R1273"
			(at 0 0 270)
			(layer "F.SilkS")
			(hide yes)
			(effects
				(font
					(size 1.27 1.27)
				)
			)
		)
		(property "Value" ""
			(at 0 0 270)
			(layer "F.Fab")
			(effects
				(font
					(size 1.27 1.27)
				)
			)
		)
		(duplicate_pad_numbers_are_jumpers no)
		(fp_line
			(start -0.7874 0.4064)
			(end -0.7874 -0.4064)
			(stroke
				(width 0.1524)
				(type default)
			)
			(layer "F.SilkS")
		)
		(fp_line
			(start 0.7874 0.4064)
			(end -0.7874 0.4064)
			(stroke
				(width 0.1524)
				(type default)
			)
			(layer "F.SilkS")
		)
		(fp_line
			(start -0.7874 -0.4064)
			(end 0.7874 -0.4064)
			(stroke
				(width 0.1524)
				(type default)
			)
			(layer "F.SilkS")
		)
		(fp_line
			(start 0.7874 -0.4064)
			(end 0.7874 0.4064)
			(stroke
				(width 0.1524)
				(type default)
			)
			(layer "F.SilkS")
		)
		(fp_line
			(start -0.67945 0.3048)
			(end -0.67945 -0.305054)
			(stroke
				(width 0.1)
				(type default)
			)
			(layer "F.Fab")
		)
		(fp_line
			(start -0.12065 0.3048)
			(end -0.67945 0.3048)
			(stroke
				(width 0.1)
				(type default)
			)
			(layer "F.Fab")
		)
		(fp_line
			(start 0.120396 0.3048)
			(end 0.120396 0.2794)
			(stroke
				(width 0.1)
				(type default)
			)
			(layer "F.Fab")
		)
		(fp_line
			(start 0.67945 0.3048)
			(end 0.120396 0.3048)
			(stroke
				(width 0.1)
				(type default)
			)
			(layer "F.Fab")
		)
		(fp_line
			(start -0.12065 0.2794)
			(end -0.12065 0.3048)
			(stroke
				(width 0.1)
				(type default)
			)
			(layer "F.Fab")
		)
		(fp_line
			(start 0.120396 0.2794)
			(end -0.12065 0.2794)
			(stroke
				(width 0.1)
				(type default)
			)
			(layer "F.Fab")
		)
		(fp_line
			(start -0.12065 -0.2794)
			(end 0.12065 -0.2794)
			(stroke
				(width 0.1)
				(type default)
			)
			(layer "F.Fab")
		)
		(fp_line
			(start 0.12065 -0.2794)
			(end 0.12065 -0.3048)
			(stroke
				(width 0.1)
				(type default)
			)
			(layer "F.Fab")
		)
		(fp_line
			(start 0.12065 -0.3048)
			(end 0.67945 -0.3048)
			(stroke
				(width 0.1)
				(type default)
			)
			(layer "F.Fab")
		)
		(fp_line
			(start 0.67945 -0.3048)
			(end 0.67945 0.3048)
			(stroke
				(width 0.1)
				(type default)
			)
			(layer "F.Fab")
		)
		(fp_line
			(start -0.67945 -0.305054)
			(end -0.12065 -0.305054)
			(stroke
				(width 0.1)
				(type default)
			)
			(layer "F.Fab")
		)
		(fp_line
			(start -0.12065 -0.305054)
			(end -0.12065 -0.2794)
			(stroke
				(width 0.1)
				(type default)
			)
			(layer "F.Fab")
		)
		(pad "1" smd circle
			(at -0.40005 0 270)
			(size 0 0)
			(layers "F.Cu" "F.Mask" "F.Paste")
			(net "PEX1_MODE_SEL4")
		)
		(pad "2" smd circle
			(at 0.40005 0 270)
			(size 0 0)
			(layers "F.Cu" "F.Mask" "F.Paste")
			(net "P1V8_PEX")
		)
	)
	(footprint ""
		(layer "F.Cu")
		(at 368.096292 -47.20082 90)
		(property "Reference" "C334"
			(at 0 0 90)
			(layer "F.SilkS")
			(hide yes)
			(effects
				(font
					(size 1.27 1.27)
				)
			)
		)
		(property "Value" ""
			(at 0 0 90)
			(layer "F.Fab")
			(effects
				(font
					(size 1.27 1.27)
				)
			)
		)
		(duplicate_pad_numbers_are_jumpers no)
		(fp_line
			(start 0.7874 -0.4064)
			(end 0.7874 0.4064)
			(stroke
				(width 0.1524)
				(type default)
			)
			(layer "F.SilkS")
		)
		(fp_line
			(start -0.7874 -0.4064)
			(end 0.7874 -0.4064)
			(stroke
				(width 0.1524)
				(type default)
			)
			(layer "F.SilkS")
		)
		(fp_line
			(start 0.7874 0.4064)
			(end -0.7874 0.4064)
			(stroke
				(width 0.1524)
				(type default)
			)
			(layer "F.SilkS")
		)
		(fp_line
			(start -0.7874 0.4064)
			(end -0.7874 -0.4064)
			(stroke
				(width 0.1524)
				(type default)
			)
			(layer "F.SilkS")
		)
		(fp_line
			(start -0.12065 -0.305054)
			(end -0.12065 -0.2794)
			(stroke
				(width 0.1)
				(type default)
			)
			(layer "F.Fab")
		)
		(fp_line
			(start -0.67945 -0.305054)
			(end -0.12065 -0.305054)
			(stroke
				(width 0.1)
				(type default)
			)
			(layer "F.Fab")
		)
		(fp_line
			(start 0.67945 -0.3048)
			(end 0.67945 0.3048)
			(stroke
				(width 0.1)
				(type default)
			)
			(layer "F.Fab")
		)
		(fp_line
			(start 0.12065 -0.3048)
			(end 0.67945 -0.3048)
			(stroke
				(width 0.1)
				(type default)
			)
			(layer "F.Fab")
		)
		(fp_line
			(start 0.12065 -0.2794)
			(end 0.12065 -0.3048)
			(stroke
				(width 0.1)
				(type default)
			)
			(layer "F.Fab")
		)
		(fp_line
			(start -0.12065 -0.2794)
			(end 0.12065 -0.2794)
			(stroke
				(width 0.1)
				(type default)
			)
			(layer "F.Fab")
		)
		(fp_line
			(start 0.120396 0.2794)
			(end -0.12065 0.2794)
			(stroke
				(width 0.1)
				(type default)
			)
			(layer "F.Fab")
		)
		(fp_line
			(start -0.12065 0.2794)
			(end -0.12065 0.3048)
			(stroke
				(width 0.1)
				(type default)
			)
			(layer "F.Fab")
		)
		(fp_line
			(start 0.67945 0.3048)
			(end 0.120396 0.3048)
			(stroke
				(width 0.1)
				(type default)
			)
			(layer "F.Fab")
		)
		(fp_line
			(start 0.120396 0.3048)
			(end 0.120396 0.2794)
			(stroke
				(width 0.1)
				(type default)
			)
			(layer "F.Fab")
		)
		(fp_line
			(start -0.12065 0.3048)
			(end -0.67945 0.3048)
			(stroke
				(width 0.1)
				(type default)
			)
			(layer "F.Fab")
		)
		(fp_line
			(start -0.67945 0.3048)
			(end -0.67945 -0.305054)
			(stroke
				(width 0.1)
				(type default)
			)
			(layer "F.Fab")
		)
		(pad "1" smd circle
			(at -0.40005 0 90)
			(size 0 0)
			(layers "F.Cu" "F.Mask" "F.Paste")
			(net "P12V_SSD12_R")
		)
		(pad "2" smd circle
			(at 0.40005 0 90)
			(size 0 0)
			(layers "F.Cu" "F.Mask" "F.Paste")
			(net "GND")
		)
	)
	(footprint ""
		(layer "F.Cu")
		(at 374.705372 -258.582922 90)
		(property "Reference" "L145"
			(at 0 0 90)
			(layer "F.SilkS")
			(hide yes)
			(effects
				(font
					(size 1.27 1.27)
				)
			)
		)
		(property "Value" ""
			(at 0 0 90)
			(layer "F.Fab")
			(effects
				(font
					(size 1.27 1.27)
				)
			)
		)
		(duplicate_pad_numbers_are_jumpers no)
		(fp_line
			(start 1.63576 -0.8128)
			(end 1.63576 0.8128)
			(stroke
				(width 0.1524)
				(type default)
			)
			(layer "F.SilkS")
		)
		(fp_line
			(start -1.63576 -0.8128)
			(end 1.63576 -0.8128)
			(stroke
				(width 0.1524)
				(type default)
			)
			(layer "F.SilkS")
		)
		(fp_line
			(start -1.63576 -0.8128)
			(end -1.63576 0.8128)
			(stroke
				(width 0.1524)
				(type default)
			)
			(layer "F.SilkS")
		)
		(fp_line
			(start 1.63576 0.8128)
			(end -1.63576 0.8128)
			(stroke
				(width 0.1524)
				(type default)
			)
			(layer "F.SilkS")
		)
		(fp_line
			(start 1.560576 -0.738632)
			(end -1.56083 -0.738632)
			(stroke
				(width 0.1)
				(type default)
			)
			(layer "F.Fab")
		)
		(fp_line
			(start -1.56083 -0.738632)
			(end -1.56083 0.7366)
			(stroke
				(width 0.1)
				(type default)
			)
			(layer "F.Fab")
		)
		(fp_line
			(start 1.560576 0.7366)
			(end 1.560576 -0.738632)
			(stroke
				(width 0.1)
				(type default)
			)
			(layer "F.Fab")
		)
		(fp_line
			(start 1.524 0.7366)
			(end 1.560576 0.7366)
			(stroke
				(width 0.1)
				(type default)
			)
			(layer "F.Fab")
		)
		(fp_line
			(start -1.524 0.7366)
			(end 1.524 0.7366)
			(stroke
				(width 0.1)
				(type default)
			)
			(layer "F.Fab")
		)
		(fp_line
			(start -1.56083 0.7366)
			(end -1.524 0.7366)
			(stroke
				(width 0.1)
				(type default)
			)
			(layer "F.Fab")
		)
		(pad "1" smd rect
			(at -0.94996 0 270)
			(size 1.1176 1.3716)
			(layers "F.Cu" "F.Mask" "F.Paste")
			(net "P1V8_PLL0_PEX3")
		)
		(pad "2" smd rect
			(at 0.94996 0 270)
			(size 1.1176 1.3716)
			(layers "F.Cu" "F.Mask" "F.Paste")
			(net "P1V8_VDDA_PEX3")
		)
	)
)
